#ISCELL
  cls sheet_a1 *
  *
#ISCELL
  cls offpage_in *
  page8_i1
#ISCELL
  cls vcc *
  page8_i13
#CELL
  passive capacitor *
  page8_i16
#CELL
  passive ferritebead *
  page8_i18
#CELL
  passive capacitor *
  page8_i19
#ISCELL
  cls offpage_bi *
  page8_i2
#ISCELL
  cls gnd_sg *
  page8_i20
#CELL
  passive capacitor *
  page8_i21
#ISCELL
  cls vcc *
  page8_i22
#ISCELL
  cls vcc *
  page8_i23
#CELL
  analog icp_10100_lga10 *
  page8_i24
#ISCELL
  cls gnd_sg *
  page8_i25
#CELL
  passive resistor *
  page8_i3
#CELL
  passive resistor *
  page8_i30
#CELL
  passive resistor *
  page8_i31
#CELL
  passive resistor *
  page8_i32
#CELL
  passive resistor *
  page8_i33
#CELL
  passive resistor *
  page8_i34
#ISCELL
  cls gnd_sg *
  page8_i35
#ISCELL
  cls gnd_sg *
  page8_i38
#CELL
  passive capacitor *
  page8_i39
#CELL
  passive capacitor *
  page8_i41
#ISCELL
  cls offpage_bi *
  page8_i43
#ISCELL
  cls offpage_bi *
  page8_i44
#CELL
  passive resistor *
  page8_i5
#CELL
  stdlogic pca9508dp_tssop8 *
  page8_i51
#CELL
  stdlogic pca9508dp_tssop8 *
  page8_i52
#ISCELL
  cls gnd_sg *
  page8_i53
#ISCELL
  cls vcc *
  page8_i54
#ISCELL
  cls offpage_bi *
  page8_i57
#ISCELL
  cls offpage_out *
  page8_i58
#CELL
  passive resistor *
  page8_i6
#CELL
  passive resistor *
  page8_i63
#CELL
  passive resistor *
  page8_i64
#CELL
  passive resistor *
  page8_i69
#CELL
  passive resistor *
  page8_i7
#CELL
  passive resistor *
  page8_i70
#CELL
  passive resistor *
  page8_i71
#ISCELL
  cls vcc *
  page8_i72
#ISCELL
  cls vcc *
  page8_i73
